(kicad_pcb
	(version 20260206)
	(generator "pcbnew")
	(generator_version "10.0")
	(general
		(thickness 1.6)
		(legacy_teardrops no)
	)
	(paper "A4")
	(title_block
		(title "Wiwynn_Tioga_Pass_MB.brd")
		(comment 1 "Tioga Pass / footprints 1529-1535 of 4770")
	)
	(layers
		(0 "F.Cu" signal "TOP")
		(4 "In1.Cu" signal "L2GND")
		(6 "In2.Cu" signal "L3")
		(8 "In3.Cu" signal "L4GND")
		(10 "In4.Cu" signal "L5")
		(12 "In5.Cu" signal "L6GND")
		(14 "In6.Cu" signal "L7VCC")
		(16 "In7.Cu" signal "L8VCC")
		(18 "In8.Cu" signal "L9GND")
		(20 "In9.Cu" signal "L10")
		(22 "In10.Cu" signal "L11GND")
		(24 "In11.Cu" signal "L12")
		(26 "In12.Cu" signal "L13GND")
		(2 "B.Cu" signal "BOTTOM")
		(9 "F.Adhes" user "F.Adhesive")
		(11 "B.Adhes" user "B.Adhesive")
		(13 "F.Paste" user "Package Geometry/Pastemask Top")
		(15 "B.Paste" user "Package Geometry/Pastemask Bottom")
		(5 "F.SilkS" user "Ref Des/Silkscreen Top")
		(7 "B.SilkS" user "Ref Des/Silkscreen Bottom")
		(1 "F.Mask" user "Board Geometry/Soldermask Top")
		(3 "B.Mask" user "Board Geometry/Soldermask Bottom")
		(17 "Dwgs.User" user "User.Drawings")
		(19 "Cmts.User" user "User.Comments")
		(21 "Eco1.User" user "User.Eco1")
		(23 "Eco2.User" user "User.Eco2")
		(25 "Edge.Cuts" user "Board Geometry/Outline")
		(27 "Margin" user)
		(31 "F.CrtYd" user "Package Geometry/Place Bound Top")
		(29 "B.CrtYd" user "Package Geometry/Place Bound Bottom")
		(35 "F.Fab" user "Ref Des/Assembly Top")
		(33 "B.Fab" user "Ref Des/Assembly Bottom")
	)
	(footprint ""
		(layer "F.Cu")
		(at 244.551454 -125.88113 -90)
		(property "Reference" "C5B2"
			(at 0 0 270)
			(layer "F.SilkS")
			(hide yes)
			(effects
				(font
					(size 1.27 1.27)
				)
			)
		)
		(property "Value" ""
			(at 0 0 270)
			(layer "F.Fab")
			(effects
				(font
					(size 1.27 1.27)
				)
			)
		)
		(duplicate_pad_numbers_are_jumpers no)
		(fp_rect
			(start -0.500126 1.598422)
			(end 0.500126 -0.201422)
			(stroke
				(width 0)
				(type default)
			)
			(fill no)
			(layer "F.CrtYd")
		)
		(fp_line
			(start -0.500126 1.598422)
			(end -0.500126 -0.201422)
			(stroke
				(width 0.1)
				(type default)
			)
			(layer "F.Fab")
		)
		(fp_line
			(start 0.500126 1.598422)
			(end -0.500126 1.598422)
			(stroke
				(width 0.1)
				(type default)
			)
			(layer "F.Fab")
		)
		(fp_line
			(start -0.500126 -0.201422)
			(end 0.500126 -0.201422)
			(stroke
				(width 0.1)
				(type default)
			)
			(layer "F.Fab")
		)
		(fp_line
			(start 0.500126 -0.201422)
			(end 0.500126 1.598422)
			(stroke
				(width 0.1)
				(type default)
			)
			(layer "F.Fab")
		)
		(pad "1" smd rect
			(at 0 0 180)
			(size 0.889 0.9906)
			(layers "F.Cu" "F.Mask" "F.Paste")
			(net "PVDDQ_DEF")
		)
		(pad "2" smd rect
			(at 0 1.397 180)
			(size 0.889 0.9906)
			(layers "F.Cu" "F.Mask" "F.Paste")
			(net "GND")
		)
		(zone
			(layer "F.Cu")
			(hatch none 0.5)
			(connect_pads
				(clearance 0)
			)
			(min_thickness 0.25)
			(keepout
				(tracks allowed)
				(vias not_allowed)
				(pads allowed)
				(copperpour not_allowed)
				(footprints allowed)
			)
			(placement
				(enabled no)
				(sheetname "")
			)
			(fill
				(thermal_gap 0.5)
				(thermal_bridge_width 0.5)
				(island_removal_mode 0)
			)
			(polygon
				(pts
					(xy 243.598954 -126.37643) (xy 243.598954 -125.38583) (xy 244.106954 -125.38583) (xy 244.106954 -126.37643)
				)
			)
		)
		(zone
			(layer "F.Cu")
			(hatch none 0.5)
			(connect_pads
				(clearance 0)
			)
			(min_thickness 0.25)
			(keepout
				(tracks not_allowed)
				(vias allowed)
				(pads allowed)
				(copperpour not_allowed)
				(footprints allowed)
			)
			(placement
				(enabled no)
				(sheetname "")
			)
			(fill
				(thermal_gap 0.5)
				(thermal_bridge_width 0.5)
				(island_removal_mode 0)
			)
			(polygon
				(pts
					(xy 243.598954 -126.37643) (xy 243.598954 -125.38583) (xy 244.106954 -125.38583) (xy 244.106954 -126.37643)
				)
			)
		)
	)
	(footprint ""
		(layer "F.Cu")
		(at 389.89 -87.3125 180)
		(property "Reference" "R3P2"
			(at 0 0 180)
			(layer "F.SilkS")
			(hide yes)
			(effects
				(font
					(size 1.27 1.27)
				)
			)
		)
		(property "Value" ""
			(at 0 0 180)
			(layer "F.Fab")
			(effects
				(font
					(size 1.27 1.27)
				)
			)
		)
		(duplicate_pad_numbers_are_jumpers no)
		(fp_poly
			(pts
				(xy -0.2794 -0.1016) (xy 0.2794 -0.1016) (xy 0.2794 0.9906) (xy -0.2794 0.9906)
			)
			(stroke
				(width 0)
				(type default)
			)
			(fill no)
			(layer "F.CrtYd")
		)
		(fp_line
			(start 0.2794 0.9906)
			(end 0.2794 -0.1016)
			(stroke
				(width 0.1)
				(type default)
			)
			(layer "F.Fab")
		)
		(fp_line
			(start 0.2794 -0.1016)
			(end -0.2794 -0.1016)
			(stroke
				(width 0.1)
				(type default)
			)
			(layer "F.Fab")
		)
		(fp_line
			(start -0.2794 0.9906)
			(end 0.2794 0.9906)
			(stroke
				(width 0.1)
				(type default)
			)
			(layer "F.Fab")
		)
		(fp_line
			(start -0.2794 -0.1016)
			(end -0.2794 0.9906)
			(stroke
				(width 0.1)
				(type default)
			)
			(layer "F.Fab")
		)
		(pad "1" smd rect
			(at 0 0 180)
			(size 0.508 0.508)
			(layers "F.Cu" "F.Mask" "F.Paste")
			(net "RMII_BMC_PCH_SPRNGVLLE_CRSDV")
		)
		(pad "2" smd rect
			(at 0 0.889 180)
			(size 0.508 0.508)
			(layers "F.Cu" "F.Mask" "F.Paste")
			(net "RMII_BMC_PCH_SPRNGVLLE_CRSDV_R1")
		)
		(zone
			(layer "F.Cu")
			(hatch none 0.5)
			(connect_pads
				(clearance 0)
			)
			(min_thickness 0.25)
			(keepout
				(tracks not_allowed)
				(vias allowed)
				(pads allowed)
				(copperpour not_allowed)
				(footprints allowed)
			)
			(placement
				(enabled no)
				(sheetname "")
			)
			(fill
				(thermal_gap 0.5)
				(thermal_bridge_width 0.5)
				(island_removal_mode 0)
			)
			(polygon
				(pts
					(xy 390.144 -87.9475) (xy 389.636 -87.9475) (xy 389.636 -87.5665) (xy 390.144 -87.5665)
				)
			)
		)
		(zone
			(layer "F.Cu")
			(hatch none 0.5)
			(connect_pads
				(clearance 0)
			)
			(min_thickness 0.25)
			(keepout
				(tracks allowed)
				(vias not_allowed)
				(pads allowed)
				(copperpour not_allowed)
				(footprints allowed)
			)
			(placement
				(enabled no)
				(sheetname "")
			)
			(fill
				(thermal_gap 0.5)
				(thermal_bridge_width 0.5)
				(island_removal_mode 0)
			)
			(polygon
				(pts
					(xy 390.144 -87.5665) (xy 389.636 -87.5665) (xy 389.636 -87.9475) (xy 390.144 -87.9475)
				)
			)
		)
	)
	(footprint ""
		(layer "F.Cu")
		(at 368.69624 -107.893866 180)
		(property "Reference" "C7C4"
			(at 0 0 180)
			(layer "F.SilkS")
			(hide yes)
			(effects
				(font
					(size 1.27 1.27)
				)
			)
		)
		(property "Value" ""
			(at 0 0 180)
			(layer "F.Fab")
			(effects
				(font
					(size 1.27 1.27)
				)
			)
		)
		(duplicate_pad_numbers_are_jumpers no)
		(fp_poly
			(pts
				(xy 0.3048 -0.1016) (xy 0.3048 0.9906) (xy -0.3048 0.9906) (xy -0.3048 -0.1016)
			)
			(stroke
				(width 0)
				(type default)
			)
			(fill no)
			(layer "F.CrtYd")
		)
		(fp_line
			(start 0.3048 0.9906)
			(end 0.3048 -0.1016)
			(stroke
				(width 0.1)
				(type default)
			)
			(layer "F.Fab")
		)
		(fp_line
			(start 0.3048 -0.1016)
			(end -0.3048 -0.1016)
			(stroke
				(width 0.1)
				(type default)
			)
			(layer "F.Fab")
		)
		(fp_line
			(start -0.3048 0.9906)
			(end 0.3048 0.9906)
			(stroke
				(width 0.1)
				(type default)
			)
			(layer "F.Fab")
		)
		(fp_line
			(start -0.3048 -0.1016)
			(end -0.3048 0.9906)
			(stroke
				(width 0.1)
				(type default)
			)
			(layer "F.Fab")
		)
		(pad "1" smd rect
			(at 0 0 180)
			(size 0.508 0.508)
			(layers "F.Cu" "F.Mask" "F.Paste")
			(net "XTAL_PCH_48M_IN")
		)
		(pad "2" smd rect
			(at 0 0.889 180)
			(size 0.508 0.508)
			(layers "F.Cu" "F.Mask" "F.Paste")
			(net "GND")
		)
		(zone
			(layer "F.Cu")
			(hatch none 0.5)
			(connect_pads
				(clearance 0)
			)
			(min_thickness 0.25)
			(keepout
				(tracks not_allowed)
				(vias allowed)
				(pads allowed)
				(copperpour not_allowed)
				(footprints allowed)
			)
			(placement
				(enabled no)
				(sheetname "")
			)
			(fill
				(thermal_gap 0.5)
				(thermal_bridge_width 0.5)
				(island_removal_mode 0)
			)
			(polygon
				(pts
					(xy 368.95024 -108.528866) (xy 368.44224 -108.528866) (xy 368.44224 -108.147866) (xy 368.95024 -108.147866)
				)
			)
		)
		(zone
			(layer "F.Cu")
			(hatch none 0.5)
			(connect_pads
				(clearance 0)
			)
			(min_thickness 0.25)
			(keepout
				(tracks allowed)
				(vias not_allowed)
				(pads allowed)
				(copperpour not_allowed)
				(footprints allowed)
			)
			(placement
				(enabled no)
				(sheetname "")
			)
			(fill
				(thermal_gap 0.5)
				(thermal_bridge_width 0.5)
				(island_removal_mode 0)
			)
			(polygon
				(pts
					(xy 368.95024 -108.147866) (xy 368.44224 -108.147866) (xy 368.44224 -108.528866) (xy 368.95024 -108.528866)
				)
			)
		)
	)
	(footprint ""
		(layer "F.Cu")
		(at 351.9932 -154.686 180)
		(property "Reference" "R7A20"
			(at 0 0 180)
			(layer "F.SilkS")
			(hide yes)
			(effects
				(font
					(size 1.27 1.27)
				)
			)
		)
		(property "Value" ""
			(at 0 0 180)
			(layer "F.Fab")
			(effects
				(font
					(size 1.27 1.27)
				)
			)
		)
		(duplicate_pad_numbers_are_jumpers no)
		(fp_poly
			(pts
				(xy -0.2794 -0.1016) (xy 0.2794 -0.1016) (xy 0.2794 0.9906) (xy -0.2794 0.9906)
			)
			(stroke
				(width 0)
				(type default)
			)
			(fill no)
			(layer "F.CrtYd")
		)
		(fp_line
			(start 0.2794 0.9906)
			(end 0.2794 -0.1016)
			(stroke
				(width 0.1)
				(type default)
			)
			(layer "F.Fab")
		)
		(fp_line
			(start 0.2794 -0.1016)
			(end -0.2794 -0.1016)
			(stroke
				(width 0.1)
				(type default)
			)
			(layer "F.Fab")
		)
		(fp_line
			(start -0.2794 0.9906)
			(end 0.2794 0.9906)
			(stroke
				(width 0.1)
				(type default)
			)
			(layer "F.Fab")
		)
		(fp_line
			(start -0.2794 -0.1016)
			(end -0.2794 0.9906)
			(stroke
				(width 0.1)
				(type default)
			)
			(layer "F.Fab")
		)
		(pad "1" smd rect
			(at 0 0 180)
			(size 0.508 0.508)
			(layers "F.Cu" "F.Mask" "F.Paste")
			(net "VR_PVDDQ_DEF_PH1_OCSET")
		)
		(pad "2" smd rect
			(at 0 0.889 180)
			(size 0.508 0.508)
			(layers "F.Cu" "F.Mask" "F.Paste")
			(net "GND")
		)
		(zone
			(layer "F.Cu")
			(hatch none 0.5)
			(connect_pads
				(clearance 0)
			)
			(min_thickness 0.25)
			(keepout
				(tracks not_allowed)
				(vias allowed)
				(pads allowed)
				(copperpour not_allowed)
				(footprints allowed)
			)
			(placement
				(enabled no)
				(sheetname "")
			)
			(fill
				(thermal_gap 0.5)
				(thermal_bridge_width 0.5)
				(island_removal_mode 0)
			)
			(polygon
				(pts
					(xy 352.2472 -155.321) (xy 351.7392 -155.321) (xy 351.7392 -154.94) (xy 352.2472 -154.94)
				)
			)
		)
		(zone
			(layer "F.Cu")
			(hatch none 0.5)
			(connect_pads
				(clearance 0)
			)
			(min_thickness 0.25)
			(keepout
				(tracks allowed)
				(vias not_allowed)
				(pads allowed)
				(copperpour not_allowed)
				(footprints allowed)
			)
			(placement
				(enabled no)
				(sheetname "")
			)
			(fill
				(thermal_gap 0.5)
				(thermal_bridge_width 0.5)
				(island_removal_mode 0)
			)
			(polygon
				(pts
					(xy 352.2472 -154.94) (xy 351.7392 -154.94) (xy 351.7392 -155.321) (xy 352.2472 -155.321)
				)
			)
		)
	)
	(footprint ""
		(layer "F.Cu")
		(at 187.833 -63.627 -90)
		(property "Reference" "R4E8"
			(at 0 0 270)
			(layer "F.SilkS")
			(hide yes)
			(effects
				(font
					(size 1.27 1.27)
				)
			)
		)
		(property "Value" ""
			(at 0 0 270)
			(layer "F.Fab")
			(effects
				(font
					(size 1.27 1.27)
				)
			)
		)
		(duplicate_pad_numbers_are_jumpers no)
		(fp_poly
			(pts
				(xy -0.2794 -0.1016) (xy 0.2794 -0.1016) (xy 0.2794 0.9906) (xy -0.2794 0.9906)
			)
			(stroke
				(width 0)
				(type default)
			)
			(fill no)
			(layer "F.CrtYd")
		)
		(fp_line
			(start -0.2794 0.9906)
			(end 0.2794 0.9906)
			(stroke
				(width 0.1)
				(type default)
			)
			(layer "F.Fab")
		)
		(fp_line
			(start 0.2794 0.9906)
			(end 0.2794 -0.1016)
			(stroke
				(width 0.1)
				(type default)
			)
			(layer "F.Fab")
		)
		(fp_line
			(start -0.2794 -0.1016)
			(end -0.2794 0.9906)
			(stroke
				(width 0.1)
				(type default)
			)
			(layer "F.Fab")
		)
		(fp_line
			(start 0.2794 -0.1016)
			(end -0.2794 -0.1016)
			(stroke
				(width 0.1)
				(type default)
			)
			(layer "F.Fab")
		)
		(pad "1" smd rect
			(at 0 0 270)
			(size 0.508 0.508)
			(layers "F.Cu" "F.Mask" "F.Paste")
			(net "VSENSE_PVCCIN_CPU0_P")
		)
		(pad "2" smd rect
			(at 0 0.889 270)
			(size 0.508 0.508)
			(layers "F.Cu" "F.Mask" "F.Paste")
			(net "VSENSE_PVCCIN_CPU0_AVSP")
		)
		(zone
			(layer "F.Cu")
			(hatch none 0.5)
			(connect_pads
				(clearance 0)
			)
			(min_thickness 0.25)
			(keepout
				(tracks not_allowed)
				(vias allowed)
				(pads allowed)
				(copperpour not_allowed)
				(footprints allowed)
			)
			(placement
				(enabled no)
				(sheetname "")
			)
			(fill
				(thermal_gap 0.5)
				(thermal_bridge_width 0.5)
				(island_removal_mode 0)
			)
			(polygon
				(pts
					(xy 187.198 -63.881) (xy 187.198 -63.373) (xy 187.579 -63.373) (xy 187.579 -63.881)
				)
			)
		)
		(zone
			(layer "F.Cu")
			(hatch none 0.5)
			(connect_pads
				(clearance 0)
			)
			(min_thickness 0.25)
			(keepout
				(tracks allowed)
				(vias not_allowed)
				(pads allowed)
				(copperpour not_allowed)
				(footprints allowed)
			)
			(placement
				(enabled no)
				(sheetname "")
			)
			(fill
				(thermal_gap 0.5)
				(thermal_bridge_width 0.5)
				(island_removal_mode 0)
			)
			(polygon
				(pts
					(xy 187.579 -63.881) (xy 187.579 -63.373) (xy 187.198 -63.373) (xy 187.198 -63.881)
				)
			)
		)
	)
	(footprint ""
		(layer "F.Cu")
		(at 422.2115 -113.03 -90)
		(property "Reference" "R9W16"
			(at -0.8382 -0.67818 270)
			(unlocked yes)
			(layer "F.SilkS")
			(effects
				(font
					(size 0.4064 0.254)
					(thickness 0.1524)
				)
				(justify left)
			)
		)
		(property "Value" ""
			(at 0 0 270)
			(layer "F.Fab")
			(effects
				(font
					(size 1.27 1.27)
				)
			)
		)
		(duplicate_pad_numbers_are_jumpers no)
		(fp_poly
			(pts
				(xy -0.2794 -0.1016) (xy 0.2794 -0.1016) (xy 0.2794 0.9906) (xy -0.2794 0.9906)
			)
			(stroke
				(width 0)
				(type default)
			)
			(fill no)
			(layer "F.CrtYd")
		)
		(fp_line
			(start -0.2794 0.9906)
			(end 0.2794 0.9906)
			(stroke
				(width 0.1)
				(type default)
			)
			(layer "F.Fab")
		)
		(fp_line
			(start 0.2794 0.9906)
			(end 0.2794 -0.1016)
			(stroke
				(width 0.1)
				(type default)
			)
			(layer "F.Fab")
		)
		(fp_line
			(start -0.2794 -0.1016)
			(end -0.2794 0.9906)
			(stroke
				(width 0.1)
				(type default)
			)
			(layer "F.Fab")
		)
		(fp_line
			(start 0.2794 -0.1016)
			(end -0.2794 -0.1016)
			(stroke
				(width 0.1)
				(type default)
			)
			(layer "F.Fab")
		)
		(pad "1" smd rect
			(at 0 0 270)
			(size 0.508 0.508)
			(layers "F.Cu" "F.Mask" "F.Paste")
			(net "P3V3_STBY")
		)
		(pad "2" smd rect
			(at 0 0.889 270)
			(size 0.508 0.508)
			(layers "F.Cu" "F.Mask" "F.Paste")
			(net "SMB_PEHPCPU0_STBY_LVC3_R_SDA")
		)
		(zone
			(layer "F.Cu")
			(hatch none 0.5)
			(connect_pads
				(clearance 0)
			)
			(min_thickness 0.25)
			(keepout
				(tracks not_allowed)
				(vias allowed)
				(pads allowed)
				(copperpour not_allowed)
				(footprints allowed)
			)
			(placement
				(enabled no)
				(sheetname "")
			)
			(fill
				(thermal_gap 0.5)
				(thermal_bridge_width 0.5)
				(island_removal_mode 0)
			)
			(polygon
				(pts
					(xy 421.5765 -113.284) (xy 421.5765 -112.776) (xy 421.9575 -112.776) (xy 421.9575 -113.284)
				)
			)
		)
		(zone
			(layer "F.Cu")
			(hatch none 0.5)
			(connect_pads
				(clearance 0)
			)
			(min_thickness 0.25)
			(keepout
				(tracks allowed)
				(vias not_allowed)
				(pads allowed)
				(copperpour not_allowed)
				(footprints allowed)
			)
			(placement
				(enabled no)
				(sheetname "")
			)
			(fill
				(thermal_gap 0.5)
				(thermal_bridge_width 0.5)
				(island_removal_mode 0)
			)
			(polygon
				(pts
					(xy 421.9575 -113.284) (xy 421.9575 -112.776) (xy 421.5765 -112.776) (xy 421.5765 -113.284)
				)
			)
		)
	)
	(footprint ""
		(layer "F.Cu")
		(at 14.36116 4.269232)
		(property "Reference" "C1G27"
			(at 0 0 0)
			(layer "F.SilkS")
			(hide yes)
			(effects
				(font
					(size 1.27 1.27)
				)
			)
		)
		(property "Value" ""
			(at 0 0 0)
			(layer "F.Fab")
			(effects
				(font
					(size 1.27 1.27)
				)
			)
		)
		(duplicate_pad_numbers_are_jumpers no)
		(fp_poly
			(pts
				(xy 0.3048 -0.1016) (xy 0.3048 0.9906) (xy -0.3048 0.9906) (xy -0.3048 -0.1016)
			)
			(stroke
				(width 0)
				(type default)
			)
			(fill no)
			(layer "F.CrtYd")
		)
		(fp_line
			(start -0.3048 -0.1016)
			(end -0.3048 0.9906)
			(stroke
				(width 0.1)
				(type default)
			)
			(layer "F.Fab")
		)
		(fp_line
			(start -0.3048 0.9906)
			(end 0.3048 0.9906)
			(stroke
				(width 0.1)
				(type default)
			)
			(layer "F.Fab")
		)
		(fp_line
			(start 0.3048 -0.1016)
			(end -0.3048 -0.1016)
			(stroke
				(width 0.1)
				(type default)
			)
			(layer "F.Fab")
		)
		(fp_line
			(start 0.3048 0.9906)
			(end 0.3048 -0.1016)
			(stroke
				(width 0.1)
				(type default)
			)
			(layer "F.Fab")
		)
		(pad "1" smd rect
			(at 0 0)
			(size 0.508 0.508)
			(layers "F.Cu" "F.Mask" "F.Paste")
			(net "VR_PVDDQ_GHJ_VDD")
		)
		(pad "2" smd rect
			(at 0 0.889)
			(size 0.508 0.508)
			(layers "F.Cu" "F.Mask" "F.Paste")
			(net "GND")
		)
		(zone
			(layer "F.Cu")
			(hatch none 0.5)
			(connect_pads
				(clearance 0)
			)
			(min_thickness 0.25)
			(keepout
				(tracks allowed)
				(vias not_allowed)
				(pads allowed)
				(copperpour not_allowed)
				(footprints allowed)
			)
			(placement
				(enabled no)
				(sheetname "")
			)
			(fill
				(thermal_gap 0.5)
				(thermal_bridge_width 0.5)
				(island_removal_mode 0)
			)
			(polygon
				(pts
					(xy 14.10716 4.523232) (xy 14.61516 4.523232) (xy 14.61516 4.904232) (xy 14.10716 4.904232)
				)
			)
		)
		(zone
			(layer "F.Cu")
			(hatch none 0.5)
			(connect_pads
				(clearance 0)
			)
			(min_thickness 0.25)
			(keepout
				(tracks not_allowed)
				(vias allowed)
				(pads allowed)
				(copperpour not_allowed)
				(footprints allowed)
			)
			(placement
				(enabled no)
				(sheetname "")
			)
			(fill
				(thermal_gap 0.5)
				(thermal_bridge_width 0.5)
				(island_removal_mode 0)
			)
			(polygon
				(pts
					(xy 14.10716 4.904232) (xy 14.61516 4.904232) (xy 14.61516 4.523232) (xy 14.10716 4.523232)
				)
			)
		)
	)
)
